(kicad_pcb
	(version 20260206)
	(generator "pcbnew")
	(generator_version "10.0")
	(general
		(thickness 1.6)
		(legacy_teardrops no)
	)
	(paper "A4")
	(title_block
		(title "panther-plus-userver — 13130-1b_20150205.brd")
		(comment 1 "Honey Badger (Wiwynn) / footprint 624 of 1509 (DIMM4), pads 100-106 of 210")
	)
	(layers
		(0 "F.Cu" signal "TOP")
		(4 "In1.Cu" signal "L2")
		(6 "In2.Cu" signal "L3")
		(8 "In3.Cu" signal "L4")
		(10 "In4.Cu" signal "L5")
		(12 "In5.Cu" signal "L6")
		(14 "In6.Cu" signal "L7")
		(16 "In7.Cu" signal "L8")
		(18 "In8.Cu" signal "L9")
		(20 "In9.Cu" signal "L10")
		(22 "In10.Cu" signal "L11")
		(2 "B.Cu" signal "BOTTOM")
		(9 "F.Adhes" user "F.Adhesive")
		(11 "B.Adhes" user "B.Adhesive")
		(13 "F.Paste" user "Package Geometry/Pastemask Top")
		(15 "B.Paste" user "Package Geometry/Pastemask Bottom")
		(5 "F.SilkS" user "Ref Des/Silkscreen Top")
		(7 "B.SilkS" user "Ref Des/Silkscreen Bottom")
		(1 "F.Mask" user "Board Geometry/Soldermask Top")
		(3 "B.Mask" user "Board Geometry/Soldermask Bottom")
		(17 "Dwgs.User" user "User.Drawings")
		(19 "Cmts.User" user "User.Comments")
		(21 "Eco1.User" user "User.Eco1")
		(23 "Eco2.User" user "User.Eco2")
		(25 "Edge.Cuts" user "Board Geometry/Outline")
		(27 "Margin" user)
		(31 "F.CrtYd" user "Package Geometry/Place Bound Top")
		(29 "B.CrtYd" user "Package Geometry/Place Bound Bottom")
		(35 "F.Fab" user "Ref Des/Assembly Top")
		(33 "B.Fab" user "Ref Des/Assembly Bottom")
	)
	(footprint ""
		(layer "F.Cu")
		(at 159.999934 -5.790692)
		(property "Reference" "DIMM4"
			(at 0 0 0)
			(layer "F.SilkS")
			(hide yes)
			(effects
				(font
					(size 1.27 1.27)
				)
			)
		)
		(property "Value" "DDR3-204P-174-COLAY-1-GP"
			(at -40.682164 -17.468088 0)
			(unlocked yes)
			(layer "F.Fab")
			(hide yes)
			(effects
				(font
					(size 1.016 1.016)
					(thickness 0.1524)
				)
			)
		)
		(property "Device Type" "AS0A626-H8SN-7H-COLAY-1"
			(at -40.682164 -18.992088 0)
			(unlocked yes)
			(layer "F.Fab")
			(hide yes)
			(effects
				(font
					(size 1.016 1.016)
					(thickness 0.1524)
				)
			)
		)
		(duplicate_pad_numbers_are_jumpers no)
		(pad "98" smd custom
			(at -0.150114 -4.106672)
			(size 0.1143 0.1143)
			(layers "F.Cu" "F.Mask" "F.Paste")
			(net "M_B_MA7")
			(options
				(clearance outline)
				(anchor circle)
			)
			(primitives
				(gr_poly
					(pts
						(xy 0 0.9017) (xy -0.03175 0.89916) (xy -0.0635 0.889) (xy -0.09144 0.87376) (xy -0.11684 0.85344)
						(xy -0.13716 0.82804) (xy -0.1524 0.8001) (xy -0.16256 0.76835) (xy -0.1651 0.7366) (xy -0.1651 0.44958)
						(xy -0.17272 0.44196) (xy -0.19812 0.4064) (xy -0.2032 0.39624) (xy -0.20701 0.38735) (xy -0.21209 0.37719)
						(xy -0.2159 0.36703) (xy -0.21844 0.35687) (xy -0.22225 0.34544) (xy -0.22352 0.33528) (xy -0.22606 0.32512)
						(xy -0.22733 0.31369) (xy -0.22733 0.30353) (xy -0.2286 0.2921) (xy -0.22733 0.28067) (xy -0.22733 0.27051)
						(xy -0.22606 0.25908) (xy -0.22352 0.24892) (xy -0.22225 0.23876) (xy -0.21844 0.22733) (xy -0.2159 0.21717)
						(xy -0.21209 0.20701) (xy -0.20701 0.19685) (xy -0.2032 0.18796) (xy -0.19812 0.1778) (xy -0.17272 0.14224)
						(xy -0.1651 0.13462) (xy -0.1651 -0.7366) (xy -0.16256 -0.76835) (xy -0.1524 -0.8001) (xy -0.13716 -0.82804)
						(xy -0.11684 -0.85344) (xy -0.09144 -0.87376) (xy -0.0635 -0.889) (xy -0.03175 -0.89916) (xy 0 -0.9017)
						(xy 0.03175 -0.89916) (xy 0.0635 -0.889) (xy 0.09144 -0.87376) (xy 0.11684 -0.85344) (xy 0.13716 -0.82804)
						(xy 0.1524 -0.8001) (xy 0.16256 -0.76835) (xy 0.1651 -0.7366) (xy 0.1651 0.13462) (xy 0.17272 0.14224)
						(xy 0.19812 0.1778) (xy 0.2032 0.18796) (xy 0.20701 0.19685) (xy 0.21209 0.20701) (xy 0.2159 0.21717)
						(xy 0.21844 0.22733) (xy 0.22225 0.23876) (xy 0.22352 0.24892) (xy 0.22606 0.25908) (xy 0.22733 0.27051)
						(xy 0.22733 0.28067) (xy 0.2286 0.2921) (xy 0.22733 0.30353) (xy 0.22733 0.31369) (xy 0.22606 0.32512)
						(xy 0.22352 0.33528) (xy 0.22225 0.34544) (xy 0.21844 0.35687) (xy 0.2159 0.36703) (xy 0.21209 0.37719)
						(xy 0.20701 0.38735) (xy 0.2032 0.39624) (xy 0.19812 0.4064) (xy 0.17272 0.44196) (xy 0.1651 0.44958)
						(xy 0.1651 0.7366) (xy 0.16256 0.76835) (xy 0.1524 0.8001) (xy 0.13716 0.82804) (xy 0.11684 0.85344)
						(xy 0.09144 0.87376) (xy 0.0635 0.889) (xy 0.03175 0.89916)
					)
					(width 0)
					(fill yes)
				)
			)
		)
		(pad "99" smd custom
			(at 0.150114 4.106672)
			(size 0.1143 0.1143)
			(layers "F.Cu" "F.Mask" "F.Paste")
			(net "M_B_MA5")
			(options
				(clearance outline)
				(anchor circle)
			)
			(primitives
				(gr_poly
					(pts
						(xy 0 0.9017) (xy -0.03175 0.89916) (xy -0.0635 0.889) (xy -0.09144 0.87376) (xy -0.11684 0.85344)
						(xy -0.13716 0.82804) (xy -0.1524 0.8001) (xy -0.16256 0.76835) (xy -0.1651 0.7366) (xy -0.1651 0.11938)
						(xy -0.17272 0.11176) (xy -0.19812 0.0762) (xy -0.2032 0.06604) (xy -0.20701 0.05715) (xy -0.21209 0.04699)
						(xy -0.2159 0.03683) (xy -0.21844 0.02667) (xy -0.22225 0.01524) (xy -0.22352 0.00508) (xy -0.22606 -0.00508)
						(xy -0.22733 -0.01651) (xy -0.22733 -0.02667) (xy -0.2286 -0.0381) (xy -0.22733 -0.04953) (xy -0.22733 -0.05969)
						(xy -0.22606 -0.07112) (xy -0.22352 -0.08128) (xy -0.22225 -0.09144) (xy -0.21844 -0.10287) (xy -0.2159 -0.11303)
						(xy -0.21209 -0.12319) (xy -0.20701 -0.13335) (xy -0.2032 -0.14224) (xy -0.19812 -0.1524) (xy -0.17272 -0.18796)
						(xy -0.1651 -0.19558) (xy -0.1651 -0.7366) (xy -0.16256 -0.76835) (xy -0.1524 -0.8001) (xy -0.13716 -0.82804)
						(xy -0.11684 -0.85344) (xy -0.09144 -0.87376) (xy -0.0635 -0.889) (xy -0.03175 -0.89916) (xy 0 -0.9017)
						(xy 0.03175 -0.89916) (xy 0.0635 -0.889) (xy 0.09144 -0.87376) (xy 0.11684 -0.85344) (xy 0.13716 -0.82804)
						(xy 0.1524 -0.8001) (xy 0.16256 -0.76835) (xy 0.1651 -0.7366) (xy 0.1651 -0.19685) (xy 0.17272 -0.18923)
						(xy 0.17907 -0.18034) (xy 0.18669 -0.17145) (xy 0.19177 -0.16256) (xy 0.19812 -0.15367) (xy 0.20828 -0.13335)
						(xy 0.21971 -0.10287) (xy 0.22225 -0.09271) (xy 0.22479 -0.08128) (xy 0.22606 -0.07112) (xy 0.2286 -0.05969)
						(xy 0.2286 -0.01651) (xy 0.22606 -0.00508) (xy 0.22479 0.00508) (xy 0.22225 0.01651) (xy 0.21971 0.02667)
						(xy 0.20828 0.05715) (xy 0.19812 0.07747) (xy 0.19177 0.08636) (xy 0.18669 0.09525) (xy 0.17907 0.10414)
						(xy 0.17272 0.11303) (xy 0.1651 0.12065) (xy 0.1651 0.7366) (xy 0.16256 0.76835) (xy 0.1524 0.8001)
						(xy 0.13716 0.82804) (xy 0.11684 0.85344) (xy 0.09144 0.87376) (xy 0.0635 0.889) (xy 0.03175 0.89916)
					)
					(width 0)
					(fill yes)
				)
			)
		)
		(pad "100" smd custom
			(at 0.450088 -4.106672)
			(size 0.1143 0.1143)
			(layers "F.Cu" "F.Mask" "F.Paste")
			(net "M_B_MA6")
			(options
				(clearance outline)
				(anchor circle)
			)
			(primitives
				(gr_poly
					(pts
						(xy 0 0.9017) (xy -0.03175 0.89916) (xy -0.0635 0.889) (xy -0.09144 0.87376) (xy -0.11684 0.85344)
						(xy -0.13716 0.82804) (xy -0.1524 0.8001) (xy -0.16256 0.76835) (xy -0.1651 0.7366) (xy -0.1651 0.19685)
						(xy -0.17272 0.18923) (xy -0.17907 0.18034) (xy -0.18669 0.17145) (xy -0.19177 0.16256) (xy -0.19812 0.15367)
						(xy -0.20828 0.13335) (xy -0.21971 0.10287) (xy -0.22225 0.09271) (xy -0.22479 0.08128) (xy -0.22606 0.07112)
						(xy -0.2286 0.05969) (xy -0.2286 0.01651) (xy -0.22606 0.00508) (xy -0.22479 -0.00508) (xy -0.22225 -0.01651)
						(xy -0.21971 -0.02667) (xy -0.20828 -0.05715) (xy -0.19812 -0.07747) (xy -0.19177 -0.08636) (xy -0.18669 -0.09525)
						(xy -0.17907 -0.10414) (xy -0.17272 -0.11303) (xy -0.1651 -0.12065) (xy -0.1651 -0.7366) (xy -0.16256 -0.76835)
						(xy -0.1524 -0.8001) (xy -0.13716 -0.82804) (xy -0.11684 -0.85344) (xy -0.09144 -0.87376) (xy -0.0635 -0.889)
						(xy -0.03175 -0.89916) (xy 0 -0.9017) (xy 0.03175 -0.89916) (xy 0.0635 -0.889) (xy 0.09144 -0.87376)
						(xy 0.11684 -0.85344) (xy 0.13716 -0.82804) (xy 0.1524 -0.8001) (xy 0.16256 -0.76835) (xy 0.1651 -0.7366)
						(xy 0.1651 -0.11938) (xy 0.17272 -0.11176) (xy 0.19812 -0.0762) (xy 0.2032 -0.06604) (xy 0.20701 -0.05715)
						(xy 0.21209 -0.04699) (xy 0.2159 -0.03683) (xy 0.21844 -0.02667) (xy 0.22225 -0.01524) (xy 0.22352 -0.00508)
						(xy 0.22606 0.00508) (xy 0.22733 0.01651) (xy 0.22733 0.02667) (xy 0.2286 0.0381) (xy 0.22733 0.04953)
						(xy 0.22733 0.05969) (xy 0.22606 0.07112) (xy 0.22352 0.08128) (xy 0.22225 0.09144) (xy 0.21844 0.10287)
						(xy 0.2159 0.11303) (xy 0.21209 0.12319) (xy 0.20701 0.13335) (xy 0.2032 0.14224) (xy 0.19812 0.1524)
						(xy 0.17272 0.18796) (xy 0.1651 0.19558) (xy 0.1651 0.7366) (xy 0.16256 0.76835) (xy 0.1524 0.8001)
						(xy 0.13716 0.82804) (xy 0.11684 0.85344) (xy 0.09144 0.87376) (xy 0.0635 0.889) (xy 0.03175 0.89916)
					)
					(width 0)
					(fill yes)
				)
			)
		)
		(pad "101" smd custom
			(at 0.750062 4.106672)
			(size 0.1143 0.1143)
			(layers "F.Cu" "F.Mask" "F.Paste")
			(net "PV_VDDR")
			(options
				(clearance outline)
				(anchor circle)
			)
			(primitives
				(gr_poly
					(pts
						(xy 0 0.9017) (xy -0.03175 0.89916) (xy -0.0635 0.889) (xy -0.09144 0.87376) (xy -0.11684 0.85344)
						(xy -0.13716 0.82804) (xy -0.1524 0.8001) (xy -0.16256 0.76835) (xy -0.1651 0.7366) (xy -0.1651 -0.13462)
						(xy -0.17272 -0.14224) (xy -0.19812 -0.1778) (xy -0.2032 -0.18796) (xy -0.20701 -0.19685) (xy -0.21209 -0.20701)
						(xy -0.2159 -0.21717) (xy -0.21844 -0.22733) (xy -0.22225 -0.23876) (xy -0.22352 -0.24892) (xy -0.22606 -0.25908)
						(xy -0.22733 -0.27051) (xy -0.22733 -0.28067) (xy -0.2286 -0.2921) (xy -0.22733 -0.30353) (xy -0.22733 -0.31369)
						(xy -0.22606 -0.32512) (xy -0.22352 -0.33528) (xy -0.22225 -0.34544) (xy -0.21844 -0.35687) (xy -0.2159 -0.36703)
						(xy -0.21209 -0.37719) (xy -0.20701 -0.38735) (xy -0.2032 -0.39624) (xy -0.19812 -0.4064) (xy -0.17272 -0.44196)
						(xy -0.1651 -0.44958) (xy -0.1651 -0.7366) (xy -0.16256 -0.76835) (xy -0.1524 -0.8001) (xy -0.13716 -0.82804)
						(xy -0.11684 -0.85344) (xy -0.09144 -0.87376) (xy -0.0635 -0.889) (xy -0.03175 -0.89916) (xy 0 -0.9017)
						(xy 0.03175 -0.89916) (xy 0.0635 -0.889) (xy 0.09144 -0.87376) (xy 0.11684 -0.85344) (xy 0.13716 -0.82804)
						(xy 0.1524 -0.8001) (xy 0.16256 -0.76835) (xy 0.1651 -0.7366) (xy 0.1651 -0.44958) (xy 0.17272 -0.44196)
						(xy 0.19812 -0.4064) (xy 0.2032 -0.39624) (xy 0.20701 -0.38735) (xy 0.21209 -0.37719) (xy 0.2159 -0.36703)
						(xy 0.21844 -0.35687) (xy 0.22225 -0.34544) (xy 0.22352 -0.33528) (xy 0.22606 -0.32512) (xy 0.22733 -0.31369)
						(xy 0.22733 -0.30353) (xy 0.2286 -0.2921) (xy 0.22733 -0.28067) (xy 0.22733 -0.27051) (xy 0.22606 -0.25908)
						(xy 0.22352 -0.24892) (xy 0.22225 -0.23876) (xy 0.21844 -0.22733) (xy 0.2159 -0.21717) (xy 0.21209 -0.20701)
						(xy 0.20701 -0.19685) (xy 0.2032 -0.18796) (xy 0.19812 -0.1778) (xy 0.17272 -0.14224) (xy 0.1651 -0.13462)
						(xy 0.1651 0.7366) (xy 0.16256 0.76835) (xy 0.1524 0.8001) (xy 0.13716 0.82804) (xy 0.11684 0.85344)
						(xy 0.09144 0.87376) (xy 0.0635 0.889) (xy 0.03175 0.89916)
					)
					(width 0)
					(fill yes)
				)
			)
		)
		(pad "102" smd custom
			(at 1.050036 -4.106672)
			(size 0.1143 0.1143)
			(layers "F.Cu" "F.Mask" "F.Paste")
			(net "PV_VDDR")
			(options
				(clearance outline)
				(anchor circle)
			)
			(primitives
				(gr_poly
					(pts
						(xy 0 0.9017) (xy -0.03175 0.89916) (xy -0.0635 0.889) (xy -0.09144 0.87376) (xy -0.11684 0.85344)
						(xy -0.13716 0.82804) (xy -0.1524 0.8001) (xy -0.16256 0.76835) (xy -0.1651 0.7366) (xy -0.1651 0.44958)
						(xy -0.17272 0.44196) (xy -0.19812 0.4064) (xy -0.2032 0.39624) (xy -0.20701 0.38735) (xy -0.21209 0.37719)
						(xy -0.2159 0.36703) (xy -0.21844 0.35687) (xy -0.22225 0.34544) (xy -0.22352 0.33528) (xy -0.22606 0.32512)
						(xy -0.22733 0.31369) (xy -0.22733 0.30353) (xy -0.2286 0.2921) (xy -0.22733 0.28067) (xy -0.22733 0.27051)
						(xy -0.22606 0.25908) (xy -0.22352 0.24892) (xy -0.22225 0.23876) (xy -0.21844 0.22733) (xy -0.2159 0.21717)
						(xy -0.21209 0.20701) (xy -0.20701 0.19685) (xy -0.2032 0.18796) (xy -0.19812 0.1778) (xy -0.17272 0.14224)
						(xy -0.1651 0.13462) (xy -0.1651 -0.7366) (xy -0.16256 -0.76835) (xy -0.1524 -0.8001) (xy -0.13716 -0.82804)
						(xy -0.11684 -0.85344) (xy -0.09144 -0.87376) (xy -0.0635 -0.889) (xy -0.03175 -0.89916) (xy 0 -0.9017)
						(xy 0.03175 -0.89916) (xy 0.0635 -0.889) (xy 0.09144 -0.87376) (xy 0.11684 -0.85344) (xy 0.13716 -0.82804)
						(xy 0.1524 -0.8001) (xy 0.16256 -0.76835) (xy 0.1651 -0.7366) (xy 0.1651 0.13462) (xy 0.17272 0.14224)
						(xy 0.19812 0.1778) (xy 0.2032 0.18796) (xy 0.20701 0.19685) (xy 0.21209 0.20701) (xy 0.2159 0.21717)
						(xy 0.21844 0.22733) (xy 0.22225 0.23876) (xy 0.22352 0.24892) (xy 0.22606 0.25908) (xy 0.22733 0.27051)
						(xy 0.22733 0.28067) (xy 0.2286 0.2921) (xy 0.22733 0.30353) (xy 0.22733 0.31369) (xy 0.22606 0.32512)
						(xy 0.22352 0.33528) (xy 0.22225 0.34544) (xy 0.21844 0.35687) (xy 0.2159 0.36703) (xy 0.21209 0.37719)
						(xy 0.20701 0.38735) (xy 0.2032 0.39624) (xy 0.19812 0.4064) (xy 0.17272 0.44196) (xy 0.1651 0.44958)
						(xy 0.1651 0.7366) (xy 0.16256 0.76835) (xy 0.1524 0.8001) (xy 0.13716 0.82804) (xy 0.11684 0.85344)
						(xy 0.09144 0.87376) (xy 0.0635 0.889) (xy 0.03175 0.89916)
					)
					(width 0)
					(fill yes)
				)
			)
		)
		(pad "103" smd custom
			(at 1.35001 4.106672)
			(size 0.1143 0.1143)
			(layers "F.Cu" "F.Mask" "F.Paste")
			(net "M_B_MA3")
			(options
				(clearance outline)
				(anchor circle)
			)
			(primitives
				(gr_poly
					(pts
						(xy 0 0.9017) (xy -0.03175 0.89916) (xy -0.0635 0.889) (xy -0.09144 0.87376) (xy -0.11684 0.85344)
						(xy -0.13716 0.82804) (xy -0.1524 0.8001) (xy -0.16256 0.76835) (xy -0.1651 0.7366) (xy -0.1651 0.11938)
						(xy -0.17272 0.11176) (xy -0.19812 0.0762) (xy -0.2032 0.06604) (xy -0.20701 0.05715) (xy -0.21209 0.04699)
						(xy -0.2159 0.03683) (xy -0.21844 0.02667) (xy -0.22225 0.01524) (xy -0.22352 0.00508) (xy -0.22606 -0.00508)
						(xy -0.22733 -0.01651) (xy -0.22733 -0.02667) (xy -0.2286 -0.0381) (xy -0.22733 -0.04953) (xy -0.22733 -0.05969)
						(xy -0.22606 -0.07112) (xy -0.22352 -0.08128) (xy -0.22225 -0.09144) (xy -0.21844 -0.10287) (xy -0.2159 -0.11303)
						(xy -0.21209 -0.12319) (xy -0.20701 -0.13335) (xy -0.2032 -0.14224) (xy -0.19812 -0.1524) (xy -0.17272 -0.18796)
						(xy -0.1651 -0.19558) (xy -0.1651 -0.7366) (xy -0.16256 -0.76835) (xy -0.1524 -0.8001) (xy -0.13716 -0.82804)
						(xy -0.11684 -0.85344) (xy -0.09144 -0.87376) (xy -0.0635 -0.889) (xy -0.03175 -0.89916) (xy 0 -0.9017)
						(xy 0.03175 -0.89916) (xy 0.0635 -0.889) (xy 0.09144 -0.87376) (xy 0.11684 -0.85344) (xy 0.13716 -0.82804)
						(xy 0.1524 -0.8001) (xy 0.16256 -0.76835) (xy 0.1651 -0.7366) (xy 0.1651 -0.19685) (xy 0.17272 -0.18923)
						(xy 0.17907 -0.18034) (xy 0.18669 -0.17145) (xy 0.19177 -0.16256) (xy 0.19812 -0.15367) (xy 0.20828 -0.13335)
						(xy 0.21971 -0.10287) (xy 0.22225 -0.09271) (xy 0.22479 -0.08128) (xy 0.22606 -0.07112) (xy 0.2286 -0.05969)
						(xy 0.2286 -0.01651) (xy 0.22606 -0.00508) (xy 0.22479 0.00508) (xy 0.22225 0.01651) (xy 0.21971 0.02667)
						(xy 0.20828 0.05715) (xy 0.19812 0.07747) (xy 0.19177 0.08636) (xy 0.18669 0.09525) (xy 0.17907 0.10414)
						(xy 0.17272 0.11303) (xy 0.1651 0.12065) (xy 0.1651 0.7366) (xy 0.16256 0.76835) (xy 0.1524 0.8001)
						(xy 0.13716 0.82804) (xy 0.11684 0.85344) (xy 0.09144 0.87376) (xy 0.0635 0.889) (xy 0.03175 0.89916)
					)
					(width 0)
					(fill yes)
				)
			)
		)
		(pad "104" smd custom
			(at 1.649984 -4.106672)
			(size 0.1143 0.1143)
			(layers "F.Cu" "F.Mask" "F.Paste")
			(net "M_B_MA4")
			(options
				(clearance outline)
				(anchor circle)
			)
			(primitives
				(gr_poly
					(pts
						(xy 0 0.9017) (xy -0.03175 0.89916) (xy -0.0635 0.889) (xy -0.09144 0.87376) (xy -0.11684 0.85344)
						(xy -0.13716 0.82804) (xy -0.1524 0.8001) (xy -0.16256 0.76835) (xy -0.1651 0.7366) (xy -0.1651 0.19685)
						(xy -0.17272 0.18923) (xy -0.17907 0.18034) (xy -0.18669 0.17145) (xy -0.19177 0.16256) (xy -0.19812 0.15367)
						(xy -0.20828 0.13335) (xy -0.21971 0.10287) (xy -0.22225 0.09271) (xy -0.22479 0.08128) (xy -0.22606 0.07112)
						(xy -0.2286 0.05969) (xy -0.2286 0.01651) (xy -0.22606 0.00508) (xy -0.22479 -0.00508) (xy -0.22225 -0.01651)
						(xy -0.21971 -0.02667) (xy -0.20828 -0.05715) (xy -0.19812 -0.07747) (xy -0.19177 -0.08636) (xy -0.18669 -0.09525)
						(xy -0.17907 -0.10414) (xy -0.17272 -0.11303) (xy -0.1651 -0.12065) (xy -0.1651 -0.7366) (xy -0.16256 -0.76835)
						(xy -0.1524 -0.8001) (xy -0.13716 -0.82804) (xy -0.11684 -0.85344) (xy -0.09144 -0.87376) (xy -0.0635 -0.889)
						(xy -0.03175 -0.89916) (xy 0 -0.9017) (xy 0.03175 -0.89916) (xy 0.0635 -0.889) (xy 0.09144 -0.87376)
						(xy 0.11684 -0.85344) (xy 0.13716 -0.82804) (xy 0.1524 -0.8001) (xy 0.16256 -0.76835) (xy 0.1651 -0.7366)
						(xy 0.1651 -0.11938) (xy 0.17272 -0.11176) (xy 0.19812 -0.0762) (xy 0.2032 -0.06604) (xy 0.20701 -0.05715)
						(xy 0.21209 -0.04699) (xy 0.2159 -0.03683) (xy 0.21844 -0.02667) (xy 0.22225 -0.01524) (xy 0.22352 -0.00508)
						(xy 0.22606 0.00508) (xy 0.22733 0.01651) (xy 0.22733 0.02667) (xy 0.2286 0.0381) (xy 0.22733 0.04953)
						(xy 0.22733 0.05969) (xy 0.22606 0.07112) (xy 0.22352 0.08128) (xy 0.22225 0.09144) (xy 0.21844 0.10287)
						(xy 0.2159 0.11303) (xy 0.21209 0.12319) (xy 0.20701 0.13335) (xy 0.2032 0.14224) (xy 0.19812 0.1524)
						(xy 0.17272 0.18796) (xy 0.1651 0.19558) (xy 0.1651 0.7366) (xy 0.16256 0.76835) (xy 0.1524 0.8001)
						(xy 0.13716 0.82804) (xy 0.11684 0.85344) (xy 0.09144 0.87376) (xy 0.0635 0.889) (xy 0.03175 0.89916)
					)
					(width 0)
					(fill yes)
				)
			)
		)
	)
)
